# TIMECARD (Time Appliance Project (Time Card)) — schematic netlist excerpt (pin names and nets, part order shuffled) for the footprints in the layout excerpt that follows; sources: Cadence DE-HDL packaged netlist, KiCad conversion of R4006-B0001-02_R01.brd

R429  RESISTOR  33OHM 1%  pkg SMC_0402R_H016  page 25 : \1\ = FPGA_IO_5 ; \2\ = UNNAMED_16_CONNHDR2X6FSSMT_I1_2
R60  RESISTOR  33OHM 1%  pkg SMC_0402R_H016  page 16 : \1\ = FPGA_OUT_PCA9546_RST_N ; \2\ = PCA9546_RST_N

(kicad_pcb
	(version 20260206)
	(generator "pcbnew")
	(generator_version "10.0")
	(general
		(thickness 1.6)
		(legacy_teardrops no)
	)
	(paper "A4")
	(title_block
		(title "timecard-production-celestica-r4006 — R4006-B0001-02_R01.brd")
		(comment 1 "Time Appliance Project (Time Card) / footprints 742-743 of 1113")
	)
	(layers
		(0 "F.Cu" signal "TOP")
		(4 "In1.Cu" signal "L02_GND1")
		(6 "In2.Cu" signal "L03_SIG1")
		(8 "In3.Cu" signal "L04_GND2")
		(10 "In4.Cu" signal "L05_VCC1")
		(12 "In5.Cu" signal "L06_VCC2")
		(14 "In6.Cu" signal "L07_GND3")
		(16 "In7.Cu" signal "L08_SIG2")
		(18 "In8.Cu" signal "L09_GND4")
		(2 "B.Cu" signal "BOTTOM")
		(9 "F.Adhes" user "F.Adhesive")
		(11 "B.Adhes" user "B.Adhesive")
		(13 "F.Paste" user "Package Geometry/Pastemask Top")
		(15 "B.Paste" user "Package Geometry/Pastemask Bottom")
		(5 "F.SilkS" user "Ref Des/Silkscreen Top")
		(7 "B.SilkS" user "Ref Des/Silkscreen Bottom")
		(1 "F.Mask" user "Board Geometry/Soldermask Top")
		(3 "B.Mask" user "Board Geometry/Soldermask Bottom")
		(17 "Dwgs.User" user "User.Drawings")
		(19 "Cmts.User" user "User.Comments")
		(21 "Eco1.User" user "User.Eco1")
		(23 "Eco2.User" user "User.Eco2")
		(25 "Edge.Cuts" user "Board Geometry/Outline")
		(27 "Margin" user)
		(31 "F.CrtYd" user "Package Geometry/Place Bound Top")
		(29 "B.CrtYd" user "Package Geometry/Place Bound Bottom")
		(35 "F.Fab" user "Ref Des/Assembly Top")
		(33 "B.Fab" user "Ref Des/Assembly Bottom")
	)
	(footprint ""
		(layer "B.Cu")
		(at 156.718 -42.037 -90)
		(property "Reference" "R429"
			(at 8.29437 0.635 0)
			(unlocked yes)
			(layer "B.SilkS")
			(effects
				(font
					(size 0.7874 0.5842)
					(thickness 0.1524)
				)
				(justify mirror)
			)
		)
		(property "Value" "VAL*"
			(at -0.02032 2.13233 270)
			(unlocked yes)
			(layer "B.Fab")
			(hide yes)
			(effects
				(font
					(size 0.7874 0.5842)
					(thickness 0.1524)
				)
				(justify mirror)
			)
		)
		(property "Tolerance" "TOL*"
			(at -0.044704 3.05435 270)
			(unlocked yes)
			(layer "Cmts.User")
			(hide yes)
			(effects
				(font
					(size 0.7874 0.5842)
					(thickness 0.1524)
				)
				(justify mirror)
			)
		)
		(property "User Part Number" "PARTNUM*"
			(at -0.02032 4.024884 270)
			(unlocked yes)
			(layer "Cmts.User")
			(hide yes)
			(effects
				(font
					(size 0.7874 0.5842)
					(thickness 0.1524)
				)
				(justify mirror)
			)
		)
		(property "Device Type" "RESISTOR-G155-133R0-01,33OHM,1%"
			(at -0.008382 1.210564 270)
			(unlocked yes)
			(layer "B.Fab")
			(hide yes)
			(effects
				(font
					(size 0.7874 0.5842)
					(thickness 0.1524)
				)
				(justify mirror)
			)
		)
		(duplicate_pad_numbers_are_jumpers no)
		(fp_line
			(start -1.143 0.5588)
			(end -1.143 -0.5588)
			(stroke
				(width 0.1)
				(type default)
			)
			(layer "B.SilkS")
		)
		(fp_line
			(start 1.143 0.5588)
			(end -1.143 0.5588)
			(stroke
				(width 0.1)
				(type default)
			)
			(layer "B.SilkS")
		)
		(fp_line
			(start -1.143 -0.5588)
			(end 1.143 -0.5588)
			(stroke
				(width 0.1)
				(type default)
			)
			(layer "B.SilkS")
		)
		(fp_line
			(start 1.143 -0.5588)
			(end 1.143 0.5588)
			(stroke
				(width 0.1)
				(type default)
			)
			(layer "B.SilkS")
		)
		(fp_poly
			(pts
				(xy 1.143 0.5588) (xy -1.143 0.5588) (xy -1.143 -0.5588) (xy 1.143 -0.5588)
			)
			(stroke
				(width 0)
				(type default)
			)
			(fill no)
			(layer "B.CrtYd")
		)
		(fp_line
			(start -0.508 0.3048)
			(end -0.508 -0.3048)
			(stroke
				(width 0.1)
				(type default)
			)
			(layer "B.Fab")
		)
		(fp_line
			(start 0.508 0.3048)
			(end -0.508 0.3048)
			(stroke
				(width 0.1)
				(type default)
			)
			(layer "B.Fab")
		)
		(fp_line
			(start -0.508 -0.3048)
			(end 0.508 -0.3048)
			(stroke
				(width 0.1)
				(type default)
			)
			(layer "B.Fab")
		)
		(fp_line
			(start 0.508 -0.3048)
			(end 0.508 0.3048)
			(stroke
				(width 0.1)
				(type default)
			)
			(layer "B.Fab")
		)
		(pad "1" smd rect
			(at 0.5334 0 90)
			(size 0.7112 0.6096)
			(layers "B.Cu" "B.Mask" "B.Paste")
			(net "FPGA_IO_5")
		)
		(pad "2" smd rect
			(at -0.5334 0 90)
			(size 0.7112 0.6096)
			(layers "B.Cu" "B.Mask" "B.Paste")
			(net "UNNAMED_16_CONNHDR2X6FSSMT_I1_2")
		)
		(zone
			(layer "B.Cu")
			(hatch none 0.5)
			(connect_pads
				(clearance 0)
			)
			(min_thickness 0.25)
			(keepout
				(tracks allowed)
				(vias not_allowed)
				(pads allowed)
				(copperpour not_allowed)
				(footprints allowed)
			)
			(placement
				(enabled no)
				(sheetname "")
			)
			(fill
				(thermal_gap 0.5)
				(thermal_bridge_width 0.5)
				(island_removal_mode 0)
			)
			(polygon
				(pts
					(xy 156.4132 -41.9608) (xy 157.0228 -41.9608) (xy 157.0228 -42.1132) (xy 156.4132 -42.1132)
				)
			)
		)
		(zone
			(layer "B.Cu")
			(hatch none 0.5)
			(connect_pads
				(clearance 0)
			)
			(min_thickness 0.25)
			(keepout
				(tracks not_allowed)
				(vias allowed)
				(pads allowed)
				(copperpour not_allowed)
				(footprints allowed)
			)
			(placement
				(enabled no)
				(sheetname "")
			)
			(fill
				(thermal_gap 0.5)
				(thermal_bridge_width 0.5)
				(island_removal_mode 0)
			)
			(polygon
				(pts
					(xy 156.4132 -41.9608) (xy 157.0228 -41.9608) (xy 157.0228 -42.1132) (xy 156.4132 -42.1132)
				)
			)
		)
	)
	(footprint ""
		(layer "B.Cu")
		(at 83.2358 -88.265 180)
		(property "Reference" "R60"
			(at 0.3048 5.29463 0)
			(unlocked yes)
			(layer "B.SilkS")
			(effects
				(font
					(size 0.7874 0.5842)
					(thickness 0.1524)
				)
				(justify mirror)
			)
		)
		(property "Value" "VAL*"
			(at -0.02032 2.13233 180)
			(unlocked yes)
			(layer "B.Fab")
			(hide yes)
			(effects
				(font
					(size 0.7874 0.5842)
					(thickness 0.1524)
				)
				(justify mirror)
			)
		)
		(property "Tolerance" "TOL*"
			(at -0.044704 3.05435 180)
			(unlocked yes)
			(layer "Cmts.User")
			(hide yes)
			(effects
				(font
					(size 0.7874 0.5842)
					(thickness 0.1524)
				)
				(justify mirror)
			)
		)
		(property "User Part Number" "PARTNUM*"
			(at -0.02032 4.024884 180)
			(unlocked yes)
			(layer "Cmts.User")
			(hide yes)
			(effects
				(font
					(size 0.7874 0.5842)
					(thickness 0.1524)
				)
				(justify mirror)
			)
		)
		(property "Device Type" "RESISTOR-G155-133R0-01,33OHM,1%"
			(at -0.008382 1.210564 180)
			(unlocked yes)
			(layer "B.Fab")
			(hide yes)
			(effects
				(font
					(size 0.7874 0.5842)
					(thickness 0.1524)
				)
				(justify mirror)
			)
		)
		(duplicate_pad_numbers_are_jumpers no)
		(fp_line
			(start 1.143 0.5588)
			(end -1.143 0.5588)
			(stroke
				(width 0.1)
				(type default)
			)
			(layer "B.SilkS")
		)
		(fp_line
			(start 1.143 -0.5588)
			(end 1.143 0.5588)
			(stroke
				(width 0.1)
				(type default)
			)
			(layer "B.SilkS")
		)
		(fp_line
			(start -1.143 0.5588)
			(end -1.143 -0.5588)
			(stroke
				(width 0.1)
				(type default)
			)
			(layer "B.SilkS")
		)
		(fp_line
			(start -1.143 -0.5588)
			(end 1.143 -0.5588)
			(stroke
				(width 0.1)
				(type default)
			)
			(layer "B.SilkS")
		)
		(fp_rect
			(start 1.143 -0.5588)
			(end -1.143 0.5588)
			(stroke
				(width 0)
				(type default)
			)
			(fill no)
			(layer "B.CrtYd")
		)
		(fp_line
			(start 0.508 0.3048)
			(end -0.508 0.3048)
			(stroke
				(width 0.1)
				(type default)
			)
			(layer "B.Fab")
		)
		(fp_line
			(start 0.508 -0.3048)
			(end 0.508 0.3048)
			(stroke
				(width 0.1)
				(type default)
			)
			(layer "B.Fab")
		)
		(fp_line
			(start -0.508 0.3048)
			(end -0.508 -0.3048)
			(stroke
				(width 0.1)
				(type default)
			)
			(layer "B.Fab")
		)
		(fp_line
			(start -0.508 -0.3048)
			(end 0.508 -0.3048)
			(stroke
				(width 0.1)
				(type default)
			)
			(layer "B.Fab")
		)
		(pad "1" smd rect
			(at 0.5334 0)
			(size 0.7112 0.6096)
			(layers "B.Cu" "B.Mask" "B.Paste")
			(net "FPGA_OUT_PCA9546_RST_N")
		)
		(pad "2" smd rect
			(at -0.5334 0)
			(size 0.7112 0.6096)
			(layers "B.Cu" "B.Mask" "B.Paste")
			(net "PCA9546_RST_N")
		)
		(zone
			(layer "B.Cu")
			(hatch none 0.5)
			(connect_pads
				(clearance 0)
			)
			(min_thickness 0.25)
			(keepout
				(tracks allowed)
				(vias not_allowed)
				(pads allowed)
				(copperpour not_allowed)
				(footprints allowed)
			)
			(placement
				(enabled no)
				(sheetname "")
			)
			(fill
				(thermal_gap 0.5)
				(thermal_bridge_width 0.5)
				(island_removal_mode 0)
			)
			(polygon
				(pts
					(xy 83.1596 -87.9602) (xy 83.312 -87.9602) (xy 83.312 -88.5698) (xy 83.1596 -88.5698)
				)
			)
		)
	)
)
